(kicad_pcb
	(version 20241229)
	(generator "pcbnew")
	(generator_version "9.0")
	(general
		(thickness 0.761)
		(legacy_teardrops no)
	)
	(paper "A4")
	(title_block
		(title " M.2 to OCuLink adapter")
		(date "2025-07-16")
		(rev "1.0.2")
		(company "Antmicro Ltd")
		(comment 1 "www.antmicro.com")
		(comment 9 "footprints 7-12 of 22")
	)
	(layers
		(0 "F.Cu" signal)
		(4 "In1.Cu" signal)
		(6 "In2.Cu" signal)
		(2 "B.Cu" signal)
		(9 "F.Adhes" user "F.Adhesive")
		(11 "B.Adhes" user "B.Adhesive")
		(13 "F.Paste" user)
		(15 "B.Paste" user)
		(5 "F.SilkS" user "F.Silkscreen")
		(7 "B.SilkS" user "B.Silkscreen")
		(1 "F.Mask" user)
		(3 "B.Mask" user)
		(17 "Dwgs.User" user "User.Drawings")
		(19 "Cmts.User" user "User.Comments")
		(21 "Eco1.User" user "User.Eco1")
		(23 "Eco2.User" user "User.Eco2")
		(25 "Edge.Cuts" user)
		(27 "Margin" user)
		(31 "F.CrtYd" user "F.Courtyard")
		(29 "B.CrtYd" user "B.Courtyard")
		(35 "F.Fab" user)
		(33 "B.Fab" user)
	)
	(footprint "antmicro-footprints:R_0402_1005Metric"
		(layer "F.Cu")
		(at 151.84 91.17 180)
		(descr "Resistor SMD 0402")
		(tags "resistor SMD 0402")
		(property "Reference" "R12"
			(at -3.61 0.47 0)
			(layer "F.SilkS")
			(effects
				(font
					(size 0.7 0.7)
					(thickness 0.15)
				)
				(justify right top)
			)
		)
		(property "Value" "R_0R_0402"
			(at -1.011843 1.772047 0)
			(layer "F.Fab")
			(effects
				(font
					(size 0.7 0.7)
					(thickness 0.15)
				)
				(justify right top)
			)
		)
		(property "Datasheet" "https://industrial.panasonic.com/cdbs/www-data/pdf/RDA0000/AOA0000C301.pdf"
			(at 0 0 0)
			(layer "F.Fab")
			(hide yes)
			(effects
				(font
					(size 1.27 1.27)
					(thickness 0.15)
				)
			)
		)
		(property "Description" "SMD Chip Resistor, Jumper, 0 ohm, 100 mW, 0402 [1005 Metric], Thick Film, General Purpose"
			(at 0 0 0)
			(layer "F.Fab")
			(hide yes)
			(effects
				(font
					(size 1.27 1.27)
					(thickness 0.15)
				)
			)
		)
		(property "MPN" "ERJ2GE0R00X"
			(at 0 0 180)
			(unlocked yes)
			(layer "F.Fab")
			(hide yes)
			(effects
				(font
					(size 1 1)
					(thickness 0.15)
				)
			)
		)
		(property "Manufacturer" "Panasonic"
			(at 0 0 180)
			(unlocked yes)
			(layer "F.Fab")
			(hide yes)
			(effects
				(font
					(size 1 1)
					(thickness 0.15)
				)
			)
		)
		(property "License" "Apache-2.0"
			(at 0 0 180)
			(unlocked yes)
			(layer "F.Fab")
			(hide yes)
			(effects
				(font
					(size 1 1)
					(thickness 0.15)
				)
			)
		)
		(property "Author" "Antmicro"
			(at 0 0 180)
			(unlocked yes)
			(layer "F.Fab")
			(hide yes)
			(effects
				(font
					(size 1 1)
					(thickness 0.15)
				)
			)
		)
		(property "Val" "0R"
			(at 0 0 180)
			(unlocked yes)
			(layer "F.Fab")
			(hide yes)
			(effects
				(font
					(size 1 1)
					(thickness 0.15)
				)
			)
		)
		(property "Tolerance" ""
			(at 0 0 180)
			(unlocked yes)
			(layer "F.Fab")
			(hide yes)
			(effects
				(font
					(size 1 1)
					(thickness 0.15)
				)
			)
		)
		(property "Current" "1A"
			(at 0 0 180)
			(unlocked yes)
			(layer "F.Fab")
			(hide yes)
			(effects
				(font
					(size 1 1)
					(thickness 0.15)
				)
			)
		)
		(sheetname "/")
		(sheetfile "antmicro-m2-oculink-adapter-hw.kicad_sch")
		(attr smd dnp)
		(fp_rect
			(start -0.925 -0.47)
			(end 0.925 0.47)
			(stroke
				(width 0.05)
				(type default)
			)
			(fill no)
			(layer "F.CrtYd")
		)
		(fp_rect
			(start -0.5 -0.25)
			(end 0.5 0.25)
			(stroke
				(width 0.15)
				(type solid)
			)
			(fill no)
			(layer "F.Fab")
		)
		(fp_text user "Author: Antmicro"
			(at -0.95 4.169 0)
			(layer "F.Fab")
			(effects
				(font
					(size 0.7 0.7)
					(thickness 0.15)
				)
				(justify right top)
			)
		)
		(fp_text user "License: Apache-2.0"
			(at -0.95 5.169 0)
			(layer "F.Fab")
			(effects
				(font
					(size 0.7 0.7)
					(thickness 0.15)
				)
				(justify right top)
			)
		)
		(fp_text user "${REFERENCE}"
			(at -0.95 3.168 0)
			(layer "F.Fab")
			(effects
				(font
					(size 0.7 0.7)
					(thickness 0.15)
				)
				(justify right top)
			)
		)
		(pad "1" smd roundrect
			(at -0.48 0 180)
			(size 0.59 0.64)
			(layers "F.Cu" "F.Mask" "F.Paste")
			(roundrect_rratio 0.25)
			(net 50 "Net-(J2-5V-PadA21)")
			(pintype "passive")
		)
		(pad "2" smd roundrect
			(at 0.48 0 180)
			(size 0.59 0.64)
			(layers "F.Cu" "F.Mask" "F.Paste")
			(roundrect_rratio 0.25)
			(net 50 "Net-(J2-5V-PadA21)")
			(pintype "passive")
		)
	)
	(footprint "antmicro-footprints:R_0402_1005Metric"
		(layer "F.Cu")
		(at 151.839541 92.222904 180)
		(descr "Resistor SMD 0402")
		(tags "resistor SMD 0402")
		(property "Reference" "R7"
			(at -1.430459 -0.437096 180)
			(layer "F.SilkS")
			(effects
				(font
					(size 0.7 0.7)
					(thickness 0.15)
				)
				(justify left bottom)
			)
		)
		(property "Value" "R_0R_0402"
			(at -1.011843 1.772047 180)
			(layer "F.Fab")
			(effects
				(font
					(size 0.7 0.7)
					(thickness 0.15)
				)
				(justify left bottom)
			)
		)
		(property "Datasheet" "https://industrial.panasonic.com/cdbs/www-data/pdf/RDA0000/AOA0000C301.pdf"
			(at 0 0 180)
			(layer "F.Fab")
			(hide yes)
			(effects
				(font
					(size 1.27 1.27)
					(thickness 0.15)
				)
			)
		)
		(property "Description" "SMD Chip Resistor, Jumper, 0 ohm, 100 mW, 0402 [1005 Metric], Thick Film, General Purpose"
			(at 0 0 180)
			(layer "F.Fab")
			(hide yes)
			(effects
				(font
					(size 1.27 1.27)
					(thickness 0.15)
				)
			)
		)
		(property "MPN" "ERJ2GE0R00X"
			(at 0 0 180)
			(unlocked yes)
			(layer "F.Fab")
			(hide yes)
			(effects
				(font
					(size 1 1)
					(thickness 0.15)
				)
			)
		)
		(property "Manufacturer" "Panasonic"
			(at 0 0 180)
			(unlocked yes)
			(layer "F.Fab")
			(hide yes)
			(effects
				(font
					(size 1 1)
					(thickness 0.15)
				)
			)
		)
		(property "License" "Apache-2.0"
			(at 0 0 180)
			(unlocked yes)
			(layer "F.Fab")
			(hide yes)
			(effects
				(font
					(size 1 1)
					(thickness 0.15)
				)
			)
		)
		(property "Author" "Antmicro"
			(at 0 0 180)
			(unlocked yes)
			(layer "F.Fab")
			(hide yes)
			(effects
				(font
					(size 1 1)
					(thickness 0.15)
				)
			)
		)
		(property "Val" "0R"
			(at 0 0 180)
			(unlocked yes)
			(layer "F.Fab")
			(hide yes)
			(effects
				(font
					(size 1 1)
					(thickness 0.15)
				)
			)
		)
		(property "Tolerance" ""
			(at 0 0 180)
			(unlocked yes)
			(layer "F.Fab")
			(hide yes)
			(effects
				(font
					(size 1 1)
					(thickness 0.15)
				)
			)
		)
		(property "Current" "1A"
			(at 0 0 180)
			(unlocked yes)
			(layer "F.Fab")
			(hide yes)
			(effects
				(font
					(size 1 1)
					(thickness 0.15)
				)
			)
		)
		(sheetname "/")
		(sheetfile "antmicro-m2-oculink-adapter-hw.kicad_sch")
		(attr smd)
		(fp_rect
			(start -0.925 -0.47)
			(end 0.925 0.47)
			(stroke
				(width 0.05)
				(type default)
			)
			(fill no)
			(layer "F.CrtYd")
		)
		(fp_rect
			(start -0.5 -0.25)
			(end 0.5 0.25)
			(stroke
				(width 0.15)
				(type solid)
			)
			(fill no)
			(layer "F.Fab")
		)
		(fp_text user "${REFERENCE}"
			(at -0.95 3.168 180)
			(layer "F.Fab")
			(effects
				(font
					(size 0.7 0.7)
					(thickness 0.15)
				)
				(justify left bottom)
			)
		)
		(fp_text user "License: Apache-2.0"
			(at 0.16 9.529 180)
			(layer "F.Fab")
			(effects
				(font
					(size 0.7 0.7)
					(thickness 0.15)
				)
				(justify left bottom)
			)
		)
		(fp_text user "Author: Antmicro"
			(at -0.95 4.169 180)
			(layer "F.Fab")
			(effects
				(font
					(size 0.7 0.7)
					(thickness 0.15)
				)
				(justify left bottom)
			)
		)
		(pad "1" smd roundrect
			(at -0.48 0 180)
			(size 0.59 0.64)
			(layers "F.Cu" "F.Mask" "F.Paste")
			(roundrect_rratio 0.25)
			(net 56 "Net-(C1-Pad2)")
			(pintype "passive")
		)
		(pad "2" smd roundrect
			(at 0.48 0 180)
			(size 0.59 0.64)
			(layers "F.Cu" "F.Mask" "F.Paste")
			(roundrect_rratio 0.25)
			(net 57 "Net-(J2-V_{ACT}_TX_3V3)")
			(pintype "passive")
		)
	)
	(footprint "antmicro-footprints:R_0201"
		(layer "F.Cu")
		(at 146.82 92.63 -90)
		(descr "Resistor SMD 0201")
		(tags "resistor SMD 0201")
		(property "Reference" "R13"
			(at -1.14 -2.44 180)
			(layer "F.SilkS")
			(effects
				(font
					(size 0.7 0.7)
					(thickness 0.15)
				)
				(justify right top)
			)
		)
		(property "Value" "R_0R_0201"
			(at 0 1.25 90)
			(layer "F.Fab")
			(effects
				(font
					(size 0.7 0.7)
					(thickness 0.15)
				)
				(justify right top)
			)
		)
		(property "Datasheet" "https://www.bourns.com/docs/product-datasheets/cr.pdf"
			(at 0 0 90)
			(layer "F.Fab")
			(hide yes)
			(effects
				(font
					(size 1.27 1.27)
					(thickness 0.15)
				)
			)
		)
		(property "Description" "SMD Chip Resistor"
			(at 0 0 90)
			(layer "F.Fab")
			(hide yes)
			(effects
				(font
					(size 1.27 1.27)
					(thickness 0.15)
				)
			)
		)
		(property "MPN" "CR0201-FX-0R00GLF"
			(at 0 0 270)
			(unlocked yes)
			(layer "F.Fab")
			(hide yes)
			(effects
				(font
					(size 1 1)
					(thickness 0.15)
				)
			)
		)
		(property "Manufacturer" "Bourns"
			(at 0 0 270)
			(unlocked yes)
			(layer "F.Fab")
			(hide yes)
			(effects
				(font
					(size 1 1)
					(thickness 0.15)
				)
			)
		)
		(property "License" "Apache-2.0"
			(at 0 0 270)
			(unlocked yes)
			(layer "F.Fab")
			(hide yes)
			(effects
				(font
					(size 1 1)
					(thickness 0.15)
				)
			)
		)
		(property "Author" "Antmicro"
			(at 0 0 270)
			(unlocked yes)
			(layer "F.Fab")
			(hide yes)
			(effects
				(font
					(size 1 1)
					(thickness 0.15)
				)
			)
		)
		(property "Val" "0R"
			(at 0 0 270)
			(unlocked yes)
			(layer "F.Fab")
			(hide yes)
			(effects
				(font
					(size 1 1)
					(thickness 0.15)
				)
			)
		)
		(property "Tolerance" "1%"
			(at 0 0 270)
			(unlocked yes)
			(layer "F.Fab")
			(hide yes)
			(effects
				(font
					(size 1 1)
					(thickness 0.15)
				)
			)
		)
		(sheetname "/")
		(sheetfile "antmicro-m2-oculink-adapter-hw.kicad_sch")
		(attr smd)
		(fp_rect
			(start -0.7 -0.35)
			(end 0.7 0.35)
			(stroke
				(width 0.05)
				(type default)
			)
			(fill no)
			(layer "F.CrtYd")
		)
		(fp_rect
			(start -0.3 -0.15)
			(end 0.298 0.148)
			(stroke
				(width 0.15)
				(type solid)
			)
			(fill no)
			(layer "F.Fab")
		)
		(fp_text user "License: Apache-2.0"
			(at -0.71 4.25 90)
			(layer "F.Fab")
			(effects
				(font
					(size 0.7 0.7)
					(thickness 0.15)
				)
				(justify right top)
			)
		)
		(fp_text user "Author: Antmicro"
			(at -0.71 5.25 90)
			(layer "F.Fab")
			(effects
				(font
					(size 0.7 0.7)
					(thickness 0.15)
				)
				(justify right top)
			)
		)
		(fp_text user "${REFERENCE}"
			(at -0.71 3.25 90)
			(layer "F.Fab")
			(effects
				(font
					(size 0.7 0.7)
					(thickness 0.15)
				)
				(justify right top)
			)
		)
		(pad "" smd roundrect
			(at -0.346 0 270)
			(size 0.318 0.36)
			(layers "F.Paste")
			(roundrect_rratio 0.25)
		)
		(pad "" smd roundrect
			(at 0.344 0 270)
			(size 0.318 0.36)
			(layers "F.Paste")
			(roundrect_rratio 0.25)
		)
		(pad "1" smd roundrect
			(at -0.32 0 270)
			(size 0.46 0.4)
			(layers "F.Cu" "F.Mask")
			(roundrect_rratio 0.25)
			(net 58 "Net-(R13-Pad1)")
			(pintype "passive")
		)
		(pad "2" smd roundrect
			(at 0.32 0 270)
			(size 0.46 0.4)
			(layers "F.Cu" "F.Mask")
			(roundrect_rratio 0.25)
			(net 54 "/~{CPRSNT}")
			(pintype "passive")
		)
	)
	(footprint "antmicro-footprints:TP_SMD_1.5mm"
		(layer "F.Cu")
		(at 136.65 101.4 180)
		(property "Reference" "TP1"
			(at 0.4045 3.53 90)
			(layer "F.SilkS")
			(effects
				(font
					(size 0.7 0.7)
					(thickness 0.15)
				)
				(justify right top)
			)
		)
		(property "Value" "TP_1.5mm_SMD"
			(at 0 1.7 0)
			(layer "F.Fab")
			(effects
				(font
					(size 0.7 0.7)
					(thickness 0.15)
				)
				(justify right top)
			)
		)
		(property "Description" "test point, SMT"
			(at 0 0 0)
			(layer "F.Fab")
			(hide yes)
			(effects
				(font
					(size 1.27 1.27)
					(thickness 0.15)
				)
			)
		)
		(property "MPN" ""
			(at 0 0 180)
			(unlocked yes)
			(layer "F.Fab")
			(hide yes)
			(effects
				(font
					(size 1 1)
					(thickness 0.15)
				)
			)
		)
		(property "Manufacturer" ""
			(at 0 0 180)
			(unlocked yes)
			(layer "F.Fab")
			(hide yes)
			(effects
				(font
					(size 1 1)
					(thickness 0.15)
				)
			)
		)
		(property "Author" "Antmicro"
			(at 0 0 180)
			(unlocked yes)
			(layer "F.Fab")
			(hide yes)
			(effects
				(font
					(size 1 1)
					(thickness 0.15)
				)
			)
		)
		(property "License" "Apache-2.0"
			(at 0 0 180)
			(unlocked yes)
			(layer "F.Fab")
			(hide yes)
			(effects
				(font
					(size 1 1)
					(thickness 0.15)
				)
			)
		)
		(sheetname "/")
		(sheetfile "antmicro-m2-oculink-adapter-hw.kicad_sch")
		(attr exclude_from_pos_files exclude_from_bom)
		(fp_circle
			(center 0 0)
			(end 0.85 0)
			(stroke
				(width 0.05)
				(type default)
			)
			(fill no)
			(layer "F.CrtYd")
		)
		(fp_text user "${REFERENCE}"
			(at -0.7 2.9 0)
			(layer "F.Fab")
			(effects
				(font
					(size 0.7 0.7)
					(thickness 0.15)
				)
				(justify right top)
			)
		)
		(fp_text user "Author: Antmicro"
			(at -0.7 4.101 0)
			(layer "F.Fab")
			(effects
				(font
					(size 0.7 0.7)
					(thickness 0.15)
				)
				(justify right top)
			)
		)
		(fp_text user "License: Apache-2.0"
			(at -0.7 5.301 0)
			(layer "F.Fab")
			(effects
				(font
					(size 0.7 0.7)
					(thickness 0.15)
				)
				(justify right top)
			)
		)
		(pad "1" smd circle
			(at 0 0 90)
			(size 1.5 1.5)
			(layers "F.Cu" "F.Mask")
			(net 55 "/~{PERST}")
			(pinfunction "1")
			(pintype "passive")
			(teardrops
				(best_length_ratio 0.5)
				(max_length 1)
				(best_width_ratio 1)
				(max_width 2)
				(curved_edges yes)
				(filter_ratio 0.9)
				(enabled no)
				(allow_two_segments yes)
				(prefer_zone_connections no)
			)
		)
	)
	(footprint "antmicro-footprints:TP_SMD_1.5mm"
		(layer "F.Cu")
		(at 136.62 103.63 180)
		(property "Reference" "TP2"
			(at -0.58 -2.95 90)
			(layer "F.SilkS")
			(effects
				(font
					(size 0.7 0.7)
					(thickness 0.15)
				)
				(justify left bottom)
			)
		)
		(property "Value" "TP_1.5mm_SMD"
			(at 0 1.7 0)
			(layer "F.Fab")
			(effects
				(font
					(size 0.7 0.7)
					(thickness 0.15)
				)
				(justify right top)
			)
		)
		(property "Description" "test point, SMT"
			(at 0 0 0)
			(layer "F.Fab")
			(hide yes)
			(effects
				(font
					(size 1.27 1.27)
					(thickness 0.15)
				)
			)
		)
		(property "MPN" ""
			(at 0 0 180)
			(unlocked yes)
			(layer "F.Fab")
			(hide yes)
			(effects
				(font
					(size 1 1)
					(thickness 0.15)
				)
			)
		)
		(property "Manufacturer" ""
			(at 0 0 180)
			(unlocked yes)
			(layer "F.Fab")
			(hide yes)
			(effects
				(font
					(size 1 1)
					(thickness 0.15)
				)
			)
		)
		(property "Author" "Antmicro"
			(at 0 0 180)
			(unlocked yes)
			(layer "F.Fab")
			(hide yes)
			(effects
				(font
					(size 1 1)
					(thickness 0.15)
				)
			)
		)
		(property "License" "Apache-2.0"
			(at 0 0 180)
			(unlocked yes)
			(layer "F.Fab")
			(hide yes)
			(effects
				(font
					(size 1 1)
					(thickness 0.15)
				)
			)
		)
		(sheetname "/")
		(sheetfile "antmicro-m2-oculink-adapter-hw.kicad_sch")
		(attr exclude_from_pos_files exclude_from_bom)
		(fp_circle
			(center 0 0)
			(end 0.85 0)
			(stroke
				(width 0.05)
				(type default)
			)
			(fill no)
			(layer "F.CrtYd")
		)
		(fp_text user "License: Apache-2.0"
			(at -0.7 5.301 0)
			(layer "F.Fab")
			(effects
				(font
					(size 0.7 0.7)
					(thickness 0.15)
				)
				(justify right top)
			)
		)
		(fp_text user "${REFERENCE}"
			(at -0.7 2.9 0)
			(layer "F.Fab")
			(effects
				(font
					(size 0.7 0.7)
					(thickness 0.15)
				)
				(justify right top)
			)
		)
		(fp_text user "Author: Antmicro"
			(at -0.7 4.101 0)
			(layer "F.Fab")
			(effects
				(font
					(size 0.7 0.7)
					(thickness 0.15)
				)
				(justify right top)
			)
		)
		(pad "1" smd circle
			(at 0 0 90)
			(size 1.5 1.5)
			(layers "F.Cu" "F.Mask")
			(net 37 "/~{WAKE}")
			(pinfunction "1")
			(pintype "passive")
			(teardrops
				(best_length_ratio 0.5)
				(max_length 1)
				(best_width_ratio 1)
				(max_width 2)
				(curved_edges yes)
				(filter_ratio 0.9)
				(enabled no)
				(allow_two_segments yes)
				(prefer_zone_connections no)
			)
		)
	)
	(footprint "antmicro-footprints:TP_SMD_1mm"
		(layer "F.Cu")
		(at 149.35 90.84)
		(property "Reference" "TP3"
			(at -0.42 -0.62 0)
			(layer "F.SilkS")
			(effects
				(font
					(size 0.7 0.7)
					(thickness 0.15)
				)
				(justify left bottom)
			)
		)
		(property "Value" "TP_1mm_SMD"
			(at 0 1.4 0)
			(layer "F.Fab")
			(effects
				(font
					(size 0.7 0.7)
					(thickness 0.15)
				)
				(justify left bottom)
			)
		)
		(property "Description" "Test point 1mm SMD"
			(at 0 0 0)
			(layer "F.Fab")
			(hide yes)
			(effects
				(font
					(size 1.27 1.27)
					(thickness 0.15)
				)
			)
		)
		(property "MPN" ""
			(at 0 0 0)
			(unlocked yes)
			(layer "F.Fab")
			(hide yes)
			(effects
				(font
					(size 1 1)
					(thickness 0.15)
				)
			)
		)
		(property "Manufacturer" ""
			(at 0 0 0)
			(unlocked yes)
			(layer "F.Fab")
			(hide yes)
			(effects
				(font
					(size 1 1)
					(thickness 0.15)
				)
			)
		)
		(property "Author" "Antmicro"
			(at 0 0 0)
			(unlocked yes)
			(layer "F.Fab")
			(hide yes)
			(effects
				(font
					(size 1 1)
					(thickness 0.15)
				)
			)
		)
		(property "License" "Apache-2.0"
			(at 0 0 0)
			(unlocked yes)
			(layer "F.Fab")
			(hide yes)
			(effects
				(font
					(size 1 1)
					(thickness 0.15)
				)
			)
		)
		(sheetname "/")
		(sheetfile "antmicro-m2-oculink-adapter-hw.kicad_sch")
		(attr exclude_from_pos_files exclude_from_bom)
		(fp_circle
			(center 0 0)
			(end 0.6 0)
			(stroke
				(width 0.05)
				(type default)
			)
			(fill no)
			(layer "F.CrtYd")
		)
		(fp_text user "${REFERENCE}"
			(at -0.5 2.8 0)
			(layer "F.Fab")
			(effects
				(font
					(size 0.7 0.7)
					(thickness 0.15)
				)
				(justify left bottom)
			)
		)
		(fp_text user "Author: Antmicro"
			(at -0.5 4 0)
			(layer "F.Fab")
			(effects
				(font
					(size 0.7 0.7)
					(thickness 0.15)
				)
				(justify left bottom)
			)
		)
		(fp_text user "License: Apache-2.0"
			(at -0.5 5.2 0)
			(layer "F.Fab")
			(effects
				(font
					(size 0.7 0.7)
					(thickness 0.15)
				)
				(justify left bottom)
			)
		)
		(pad "1" smd circle
			(at 0 0)
			(size 1 1)
			(layers "F.Cu" "F.Mask")
			(net 58 "Net-(R13-Pad1)")
			(pinfunction "1")
			(pintype "passive")
		)
	)
)
